# T6G (Grand Teton) — schematic netlist excerpt (pin names and nets, part order shuffled) for the footprints in the layout excerpt that follows; sources: Cadence DE-HDL packaged netlist, KiCad conversion of 04192023_DAF0TMB3IC0_F0TG_MB_C_brd_V02_OCP.brd

R8111  Q_RES  10K 1% EMPTY  pkg 0402LF  page 267 : A = P3V3_AUX ; B = A_HSC_LOW_GATE
R288  Q_RES  4.7K 5% EMPTY  pkg 0402LF  page 28 : A = CPU0_PWR_GD_OUT ; B = PVDD18_S5_P0

(kicad_pcb
	(version 20260206)
	(generator "pcbnew")
	(generator_version "10.0")
	(general
		(thickness 1.6)
		(legacy_teardrops no)
	)
	(paper "A4")
	(title_block
		(title "04192023_DAF0TMB3IC0_F0TG_MB_C_brd_V02_OCP.brd")
		(comment 1 "Grand Teton / footprints 7451-7452 of 8354")
	)
	(layers
		(0 "F.Cu" signal "TOP")
		(4 "In1.Cu" signal "GND")
		(6 "In2.Cu" signal "IN1")
		(8 "In3.Cu" signal "GND1")
		(10 "In4.Cu" signal "IN2")
		(12 "In5.Cu" signal "GND2")
		(14 "In6.Cu" signal "IN3")
		(16 "In7.Cu" signal "GND3")
		(18 "In8.Cu" signal "VCC")
		(20 "In9.Cu" signal "VCC1")
		(22 "In10.Cu" signal "GND4")
		(24 "In11.Cu" signal "IN4")
		(26 "In12.Cu" signal "GND5")
		(28 "In13.Cu" signal "IN5")
		(30 "In14.Cu" signal "GND6")
		(32 "In15.Cu" signal "IN6")
		(34 "In16.Cu" signal "GND7")
		(2 "B.Cu" signal "BOTTOM")
		(9 "F.Adhes" user "F.Adhesive")
		(11 "B.Adhes" user "B.Adhesive")
		(13 "F.Paste" user "Package Geometry/Pastemask Top")
		(15 "B.Paste" user "Package Geometry/Pastemask Bottom")
		(5 "F.SilkS" user "Ref Des/Silkscreen Top")
		(7 "B.SilkS" user "Ref Des/Silkscreen Bottom")
		(1 "F.Mask" user "Board Geometry/Soldermask Top")
		(3 "B.Mask" user "Board Geometry/Soldermask Bottom")
		(17 "Dwgs.User" user "User.Drawings")
		(19 "Cmts.User" user "User.Comments")
		(21 "Eco1.User" user "User.Eco1")
		(23 "Eco2.User" user "User.Eco2")
		(25 "Edge.Cuts" user "Board Geometry/Outline")
		(27 "Margin" user)
		(31 "F.CrtYd" user "Package Geometry/Place Bound Top")
		(29 "B.CrtYd" user "Package Geometry/Place Bound Bottom")
		(35 "F.Fab" user "Ref Des/Assembly Top")
		(33 "B.Fab" user "Ref Des/Assembly Bottom")
	)
	(footprint ""
		(layer "B.Cu")
		(at 406.698958 -327.910952 180)
		(property "Reference" "R288"
			(at 0 0 0)
			(layer "B.SilkS")
			(hide yes)
			(effects
				(font
					(size 1.27 1.27)
				)
				(justify mirror)
			)
		)
		(property "Value" ""
			(at 0 0 0)
			(layer "B.Fab")
			(effects
				(font
					(size 1.27 1.27)
				)
				(justify mirror)
			)
		)
		(duplicate_pad_numbers_are_jumpers no)
		(fp_line
			(start 0.7874 0.4064)
			(end 0.7874 -0.4064)
			(stroke
				(width 0.1524)
				(type default)
			)
			(layer "B.SilkS")
		)
		(fp_line
			(start 0.7874 -0.4064)
			(end -0.7874 -0.4064)
			(stroke
				(width 0.1524)
				(type default)
			)
			(layer "B.SilkS")
		)
		(fp_line
			(start -0.7874 0.4064)
			(end 0.7874 0.4064)
			(stroke
				(width 0.1524)
				(type default)
			)
			(layer "B.SilkS")
		)
		(fp_line
			(start -0.7874 -0.4064)
			(end -0.7874 0.4064)
			(stroke
				(width 0.1524)
				(type default)
			)
			(layer "B.SilkS")
		)
		(fp_line
			(start 0.67945 0.3048)
			(end 0.67945 -0.305054)
			(stroke
				(width 0.1)
				(type default)
			)
			(layer "B.Fab")
		)
		(fp_line
			(start 0.67945 -0.305054)
			(end 0.12065 -0.305054)
			(stroke
				(width 0.1)
				(type default)
			)
			(layer "B.Fab")
		)
		(fp_line
			(start 0.12065 0.3048)
			(end 0.67945 0.3048)
			(stroke
				(width 0.1)
				(type default)
			)
			(layer "B.Fab")
		)
		(fp_line
			(start 0.12065 0.2794)
			(end 0.12065 0.3048)
			(stroke
				(width 0.1)
				(type default)
			)
			(layer "B.Fab")
		)
		(fp_line
			(start 0.12065 -0.2794)
			(end -0.12065 -0.2794)
			(stroke
				(width 0.1)
				(type default)
			)
			(layer "B.Fab")
		)
		(fp_line
			(start 0.12065 -0.305054)
			(end 0.12065 -0.2794)
			(stroke
				(width 0.1)
				(type default)
			)
			(layer "B.Fab")
		)
		(fp_line
			(start -0.120396 0.3048)
			(end -0.120396 0.2794)
			(stroke
				(width 0.1)
				(type default)
			)
			(layer "B.Fab")
		)
		(fp_line
			(start -0.120396 0.2794)
			(end 0.12065 0.2794)
			(stroke
				(width 0.1)
				(type default)
			)
			(layer "B.Fab")
		)
		(fp_line
			(start -0.12065 -0.2794)
			(end -0.12065 -0.3048)
			(stroke
				(width 0.1)
				(type default)
			)
			(layer "B.Fab")
		)
		(fp_line
			(start -0.12065 -0.3048)
			(end -0.67945 -0.3048)
			(stroke
				(width 0.1)
				(type default)
			)
			(layer "B.Fab")
		)
		(fp_line
			(start -0.67945 0.3048)
			(end -0.120396 0.3048)
			(stroke
				(width 0.1)
				(type default)
			)
			(layer "B.Fab")
		)
		(fp_line
			(start -0.67945 -0.3048)
			(end -0.67945 0.3048)
			(stroke
				(width 0.1)
				(type default)
			)
			(layer "B.Fab")
		)
		(pad "1" smd circle
			(at 0.40005 0)
			(size 0 0)
			(layers "B.Cu" "B.Mask" "B.Paste")
			(net "CPU0_PWR_GD_OUT")
		)
		(pad "2" smd circle
			(at -0.40005 0)
			(size 0 0)
			(layers "B.Cu" "B.Mask" "B.Paste")
			(net "PVDD18_S5_P0")
		)
	)
	(footprint ""
		(layer "B.Cu")
		(at 175.46701 -427.92269)
		(property "Reference" "R8111"
			(at 0 0 0)
			(layer "B.SilkS")
			(hide yes)
			(effects
				(font
					(size 1.27 1.27)
				)
				(justify mirror)
			)
		)
		(property "Value" ""
			(at 0 0 0)
			(layer "B.Fab")
			(effects
				(font
					(size 1.27 1.27)
				)
				(justify mirror)
			)
		)
		(duplicate_pad_numbers_are_jumpers no)
		(fp_line
			(start -0.7874 -0.4064)
			(end -0.7874 0.4064)
			(stroke
				(width 0.1524)
				(type default)
			)
			(layer "B.SilkS")
		)
		(fp_line
			(start -0.7874 0.4064)
			(end 0.7874 0.4064)
			(stroke
				(width 0.1524)
				(type default)
			)
			(layer "B.SilkS")
		)
		(fp_line
			(start 0.7874 -0.4064)
			(end -0.7874 -0.4064)
			(stroke
				(width 0.1524)
				(type default)
			)
			(layer "B.SilkS")
		)
		(fp_line
			(start 0.7874 0.4064)
			(end 0.7874 -0.4064)
			(stroke
				(width 0.1524)
				(type default)
			)
			(layer "B.SilkS")
		)
		(fp_line
			(start -0.67945 -0.3048)
			(end -0.67945 0.3048)
			(stroke
				(width 0.1)
				(type default)
			)
			(layer "B.Fab")
		)
		(fp_line
			(start -0.67945 0.3048)
			(end -0.120396 0.3048)
			(stroke
				(width 0.1)
				(type default)
			)
			(layer "B.Fab")
		)
		(fp_line
			(start -0.12065 -0.3048)
			(end -0.67945 -0.3048)
			(stroke
				(width 0.1)
				(type default)
			)
			(layer "B.Fab")
		)
		(fp_line
			(start -0.12065 -0.2794)
			(end -0.12065 -0.3048)
			(stroke
				(width 0.1)
				(type default)
			)
			(layer "B.Fab")
		)
		(fp_line
			(start -0.120396 0.2794)
			(end 0.12065 0.2794)
			(stroke
				(width 0.1)
				(type default)
			)
			(layer "B.Fab")
		)
		(fp_line
			(start -0.120396 0.3048)
			(end -0.120396 0.2794)
			(stroke
				(width 0.1)
				(type default)
			)
			(layer "B.Fab")
		)
		(fp_line
			(start 0.12065 -0.305054)
			(end 0.12065 -0.2794)
			(stroke
				(width 0.1)
				(type default)
			)
			(layer "B.Fab")
		)
		(fp_line
			(start 0.12065 -0.2794)
			(end -0.12065 -0.2794)
			(stroke
				(width 0.1)
				(type default)
			)
			(layer "B.Fab")
		)
		(fp_line
			(start 0.12065 0.2794)
			(end 0.12065 0.3048)
			(stroke
				(width 0.1)
				(type default)
			)
			(layer "B.Fab")
		)
		(fp_line
			(start 0.12065 0.3048)
			(end 0.67945 0.3048)
			(stroke
				(width 0.1)
				(type default)
			)
			(layer "B.Fab")
		)
		(fp_line
			(start 0.67945 -0.305054)
			(end 0.12065 -0.305054)
			(stroke
				(width 0.1)
				(type default)
			)
			(layer "B.Fab")
		)
		(fp_line
			(start 0.67945 0.3048)
			(end 0.67945 -0.305054)
			(stroke
				(width 0.1)
				(type default)
			)
			(layer "B.Fab")
		)
		(pad "1" smd circle
			(at 0.40005 0 180)
			(size 0 0)
			(layers "B.Cu" "B.Mask" "B.Paste")
			(net "P3V3_AUX")
		)
		(pad "2" smd circle
			(at -0.40005 0 180)
			(size 0 0)
			(layers "B.Cu" "B.Mask" "B.Paste")
			(net "A_HSC_LOW_GATE")
		)
	)
)
